(kicad_pcb
	(version 20260206)
	(generator "pcbnew")
	(generator_version "10.0")
	(general
		(thickness 1.6)
		(legacy_teardrops no)
	)
	(paper "A4")
	(title_block
		(title "ptb — 12523-1.1018WZS1506.brd")
		(comment 1 "Open Vault / Knox (Wiwynn) / footprints 18-23 of 61")
	)
	(layers
		(0 "F.Cu" signal "TOP")
		(4 "In1.Cu" signal "L2GND")
		(6 "In2.Cu" signal "L3VCC")
		(2 "B.Cu" signal "BOTTOM")
		(9 "F.Adhes" user "F.Adhesive")
		(11 "B.Adhes" user "B.Adhesive")
		(13 "F.Paste" user "Package Geometry/Pastemask Top")
		(15 "B.Paste" user "Package Geometry/Pastemask Bottom")
		(5 "F.SilkS" user "Ref Des/Silkscreen Top")
		(7 "B.SilkS" user "Ref Des/Silkscreen Bottom")
		(1 "F.Mask" user "Board Geometry/Soldermask Top")
		(3 "B.Mask" user "Board Geometry/Soldermask Bottom")
		(17 "Dwgs.User" user "User.Drawings")
		(19 "Cmts.User" user "User.Comments")
		(21 "Eco1.User" user "User.Eco1")
		(23 "Eco2.User" user "User.Eco2")
		(25 "Edge.Cuts" user "Board Geometry/Outline")
		(27 "Margin" user)
		(31 "F.CrtYd" user "Package Geometry/Place Bound Top")
		(29 "B.CrtYd" user "Package Geometry/Place Bound Bottom")
		(35 "F.Fab" user "Ref Des/Assembly Top")
		(33 "B.Fab" user "Ref Des/Assembly Bottom")
	)
	(footprint ""
		(layer "F.Cu")
		(at 17.218914 -92.751402 -90)
		(property "Reference" "R485"
			(at 0 0 270)
			(layer "F.SilkS")
			(hide yes)
			(effects
				(font
					(size 1.27 1.27)
				)
			)
		)
		(property "Value" "0R2J-2-GP"
			(at 0.064008 -3.993896 270)
			(unlocked yes)
			(layer "F.Fab")
			(hide yes)
			(effects
				(font
					(size 1.016 1.016)
					(thickness 0.1524)
				)
			)
		)
		(property "Device Type" "R402H16"
			(at 0.064008 -5.517896 270)
			(unlocked yes)
			(layer "F.Fab")
			(hide yes)
			(effects
				(font
					(size 1.016 1.016)
					(thickness 0.1524)
				)
			)
		)
		(duplicate_pad_numbers_are_jumpers no)
		(fp_line
			(start -0.508 -0.9398)
			(end -0.508 0.9398)
			(stroke
				(width 0.1524)
				(type default)
			)
			(layer "F.SilkS")
		)
		(fp_line
			(start 0.508 -0.9398)
			(end -0.508 -0.9398)
			(stroke
				(width 0.1524)
				(type default)
			)
			(layer "F.SilkS")
		)
		(fp_rect
			(start -0.508 0.9398)
			(end 0.508 -0.9398)
			(stroke
				(width 0)
				(type default)
			)
			(fill no)
			(layer "F.CrtYd")
		)
		(fp_rect
			(start -0.508 0.9398)
			(end 0.508 -0.9398)
			(stroke
				(width 0)
				(type default)
			)
			(fill no)
			(layer "F.Fab")
		)
		(pad "1" smd custom
			(at 0 -0.4445 270)
			(size 0.1397 0.1397)
			(layers "F.Cu" "F.Mask" "F.Paste")
			(net "I2C_C_BUF_SCL")
			(options
				(clearance outline)
				(anchor circle)
			)
			(primitives
				(gr_poly
					(pts
						(arc
							(start -0.1778 -0.2794)
							(mid -0.249642 -0.249642)
							(end -0.2794 -0.1778)
						)
						(arc
							(start -0.2794 0.1778)
							(mid -0.249642 0.249642)
							(end -0.1778 0.2794)
						)
						(arc
							(start 0.1778 0.2794)
							(mid 0.249642 0.249642)
							(end 0.2794 0.1778)
						)
						(arc
							(start 0.2794 -0.1778)
							(mid 0.249642 -0.249642)
							(end 0.1778 -0.2794)
						)
					)
					(width 0)
					(fill yes)
				)
			)
		)
		(pad "2" smd custom
			(at 0 0.4445 270)
			(size 0.1397 0.1397)
			(layers "F.Cu" "F.Mask" "F.Paste")
			(net "I2C_C_BUF_SCLIN")
			(options
				(clearance outline)
				(anchor circle)
			)
			(primitives
				(gr_poly
					(pts
						(arc
							(start -0.1778 -0.2794)
							(mid -0.249642 -0.249642)
							(end -0.2794 -0.1778)
						)
						(arc
							(start -0.2794 0.1778)
							(mid -0.249642 0.249642)
							(end -0.1778 0.2794)
						)
						(arc
							(start 0.1778 0.2794)
							(mid 0.249642 0.249642)
							(end 0.2794 0.1778)
						)
						(arc
							(start 0.2794 -0.1778)
							(mid 0.249642 -0.249642)
							(end 0.1778 -0.2794)
						)
					)
					(width 0)
					(fill yes)
				)
			)
		)
	)
	(footprint ""
		(layer "F.Cu")
		(at 134.375144 -79.273908 180)
		(property "Reference" "Q33"
			(at 0 0 180)
			(layer "F.SilkS")
			(hide yes)
			(effects
				(font
					(size 1.27 1.27)
				)
			)
		)
		(property "Value" "MMBT2222A-3-GP"
			(at 0.10287 -10.29843 180)
			(unlocked yes)
			(layer "F.Fab")
			(hide yes)
			(effects
				(font
					(size 1.016 1.016)
					(thickness 0.1524)
				)
			)
		)
		(property "Device Type" "SOT23CBE2D4H44"
			(at 0.10287 -12.20343 180)
			(unlocked yes)
			(layer "F.Fab")
			(hide yes)
			(effects
				(font
					(size 1.016 1.016)
					(thickness 0.1524)
				)
			)
		)
		(duplicate_pad_numbers_are_jumpers no)
		(fp_line
			(start 1.651 1.778)
			(end 1.651 -1.778)
			(stroke
				(width 0.1524)
				(type default)
			)
			(layer "F.SilkS")
		)
		(fp_line
			(start 1.651 -1.778)
			(end -1.651 -1.778)
			(stroke
				(width 0.1524)
				(type default)
			)
			(layer "F.SilkS")
		)
		(fp_line
			(start -1.651 1.778)
			(end 1.651 1.778)
			(stroke
				(width 0.1524)
				(type default)
			)
			(layer "F.SilkS")
		)
		(fp_line
			(start -1.651 -1.778)
			(end -1.651 1.778)
			(stroke
				(width 0.1524)
				(type default)
			)
			(layer "F.SilkS")
		)
		(fp_poly
			(pts
				(xy -1.778 1.8796) (xy -1.778 -1.8796) (xy 1.778 -1.8796) (xy 1.778 1.8796)
			)
			(stroke
				(width 0)
				(type default)
			)
			(fill no)
			(layer "F.CrtYd")
		)
		(fp_poly
			(pts
				(xy -1.778 1.8796) (xy -1.778 -1.8796) (xy 1.778 -1.8796) (xy 1.778 1.8796)
			)
			(stroke
				(width 0)
				(type default)
			)
			(fill no)
			(layer "F.Fab")
		)
		(pad "B" smd custom
			(at -0.98425 0.9525 180)
			(size 0.1905 0.1905)
			(layers "F.Cu" "F.Mask" "F.Paste")
			(net "TRAY_PRESENT_OUT_NET_B")
			(options
				(clearance outline)
				(anchor circle)
			)
			(primitives
				(gr_poly
					(pts
						(arc
							(start -0.1778 0.5715)
							(mid -0.321484 0.511984)
							(end -0.381 0.3683)
						)
						(arc
							(start -0.381 -0.3683)
							(mid -0.321484 -0.511984)
							(end -0.1778 -0.5715)
						)
						(arc
							(start 0.1778 -0.5715)
							(mid 0.321484 -0.511984)
							(end 0.381 -0.3683)
						)
						(arc
							(start 0.381 0.3683)
							(mid 0.321484 0.511984)
							(end 0.1778 0.5715)
						)
					)
					(width 0)
					(fill yes)
				)
			)
		)
		(pad "C" smd custom
			(at 0 -0.9525 180)
			(size 0.1905 0.1905)
			(layers "F.Cu" "F.Mask" "F.Paste")
			(net "TRAY PRESENT_OUT#_C")
			(options
				(clearance outline)
				(anchor circle)
			)
			(primitives
				(gr_poly
					(pts
						(arc
							(start -0.1778 0.5715)
							(mid -0.321484 0.511984)
							(end -0.381 0.3683)
						)
						(arc
							(start -0.381 -0.3683)
							(mid -0.321484 -0.511984)
							(end -0.1778 -0.5715)
						)
						(arc
							(start 0.1778 -0.5715)
							(mid 0.321484 -0.511984)
							(end 0.381 -0.3683)
						)
						(arc
							(start 0.381 0.3683)
							(mid 0.321484 0.511984)
							(end 0.1778 0.5715)
						)
					)
					(width 0)
					(fill yes)
				)
			)
		)
		(pad "E" smd custom
			(at 0.98425 0.9525 180)
			(size 0.1905 0.1905)
			(layers "F.Cu" "F.Mask" "F.Paste")
			(net "GND")
			(options
				(clearance outline)
				(anchor circle)
			)
			(primitives
				(gr_poly
					(pts
						(arc
							(start -0.1778 0.5715)
							(mid -0.321484 0.511984)
							(end -0.381 0.3683)
						)
						(arc
							(start -0.381 -0.3683)
							(mid -0.321484 -0.511984)
							(end -0.1778 -0.5715)
						)
						(arc
							(start 0.1778 -0.5715)
							(mid 0.321484 -0.511984)
							(end 0.381 -0.3683)
						)
						(arc
							(start 0.381 0.3683)
							(mid 0.321484 0.511984)
							(end 0.1778 0.5715)
						)
					)
					(width 0)
					(fill yes)
				)
			)
		)
	)
	(footprint ""
		(layer "F.Cu")
		(at 8.079232 -93.708728 90)
		(property "Reference" "R389"
			(at 0 0 90)
			(layer "F.SilkS")
			(hide yes)
			(effects
				(font
					(size 1.27 1.27)
				)
			)
		)
		(property "Value" "0R2J-2-GP"
			(at 0.064008 -3.993896 90)
			(unlocked yes)
			(layer "F.Fab")
			(hide yes)
			(effects
				(font
					(size 1.016 1.016)
					(thickness 0.1524)
				)
			)
		)
		(property "Device Type" "R402H16"
			(at 0.064008 -5.517896 90)
			(unlocked yes)
			(layer "F.Fab")
			(hide yes)
			(effects
				(font
					(size 1.016 1.016)
					(thickness 0.1524)
				)
			)
		)
		(duplicate_pad_numbers_are_jumpers no)
		(fp_line
			(start 0.508 -0.9398)
			(end -0.508 -0.9398)
			(stroke
				(width 0.1524)
				(type default)
			)
			(layer "F.SilkS")
		)
		(fp_line
			(start -0.508 -0.9398)
			(end -0.508 0.9398)
			(stroke
				(width 0.1524)
				(type default)
			)
			(layer "F.SilkS")
		)
		(fp_rect
			(start -0.508 0.9398)
			(end 0.508 -0.9398)
			(stroke
				(width 0)
				(type default)
			)
			(fill no)
			(layer "F.CrtYd")
		)
		(fp_rect
			(start -0.508 0.9398)
			(end 0.508 -0.9398)
			(stroke
				(width 0)
				(type default)
			)
			(fill no)
			(layer "F.Fab")
		)
		(pad "1" smd custom
			(at 0 -0.4445 90)
			(size 0.1397 0.1397)
			(layers "F.Cu" "F.Mask" "F.Paste")
			(net "STRADDLE_I2C_C_SCL")
			(options
				(clearance outline)
				(anchor circle)
			)
			(primitives
				(gr_poly
					(pts
						(arc
							(start -0.1778 -0.2794)
							(mid -0.249642 -0.249642)
							(end -0.2794 -0.1778)
						)
						(arc
							(start -0.2794 0.1778)
							(mid -0.249642 0.249642)
							(end -0.1778 0.2794)
						)
						(arc
							(start 0.1778 0.2794)
							(mid 0.249642 0.249642)
							(end 0.2794 0.1778)
						)
						(arc
							(start 0.2794 -0.1778)
							(mid 0.249642 -0.249642)
							(end 0.1778 -0.2794)
						)
					)
					(width 0)
					(fill yes)
				)
			)
		)
		(pad "2" smd custom
			(at 0 0.4445 90)
			(size 0.1397 0.1397)
			(layers "F.Cu" "F.Mask" "F.Paste")
			(net "I2C_C_SCL")
			(options
				(clearance outline)
				(anchor circle)
			)
			(primitives
				(gr_poly
					(pts
						(arc
							(start -0.1778 -0.2794)
							(mid -0.249642 -0.249642)
							(end -0.2794 -0.1778)
						)
						(arc
							(start -0.2794 0.1778)
							(mid -0.249642 0.249642)
							(end -0.1778 0.2794)
						)
						(arc
							(start 0.1778 0.2794)
							(mid 0.249642 0.249642)
							(end 0.2794 0.1778)
						)
						(arc
							(start 0.2794 -0.1778)
							(mid 0.249642 -0.249642)
							(end 0.1778 -0.2794)
						)
					)
					(width 0)
					(fill yes)
				)
			)
		)
	)
	(footprint ""
		(layer "F.Cu")
		(at 156.920692 -103.107744)
		(property "Reference" "PR64"
			(at 0 0 0)
			(layer "F.SilkS")
			(hide yes)
			(effects
				(font
					(size 1.27 1.27)
				)
			)
		)
		(property "Value" "0R3J-0-U-GP"
			(at -0.0254 -2.5146 0)
			(unlocked yes)
			(layer "F.Fab")
			(hide yes)
			(effects
				(font
					(size 1.016 1.016)
					(thickness 0.1524)
				)
			)
		)
		(property "Device Type" "R603H22"
			(at -0.0254 -4.0386 0)
			(unlocked yes)
			(layer "F.Fab")
			(hide yes)
			(effects
				(font
					(size 1.016 1.016)
					(thickness 0.1524)
				)
			)
		)
		(duplicate_pad_numbers_are_jumpers no)
		(fp_line
			(start -0.4826 0)
			(end -0.2032 0)
			(stroke
				(width 0.2032)
				(type default)
			)
			(layer "F.SilkS")
		)
		(fp_line
			(start 0.2032 0)
			(end 0.4826 0)
			(stroke
				(width 0.2032)
				(type default)
			)
			(layer "F.SilkS")
		)
		(fp_rect
			(start -0.5842 1.3335)
			(end 0.5842 -1.3335)
			(stroke
				(width 0)
				(type default)
			)
			(fill no)
			(layer "F.CrtYd")
		)
		(fp_rect
			(start -0.5842 1.3335)
			(end 0.5842 -1.3335)
			(stroke
				(width 0)
				(type default)
			)
			(fill no)
			(layer "F.Fab")
		)
		(pad "1" smd custom
			(at 0 -0.762)
			(size 0.2159 0.2159)
			(layers "F.Cu" "F.Mask" "F.Paste")
			(net "P5VA")
			(options
				(clearance outline)
				(anchor circle)
			)
			(primitives
				(gr_poly
					(pts
						(arc
							(start -0.3302 -0.4318)
							(mid -0.402042 -0.402042)
							(end -0.4318 -0.3302)
						)
						(arc
							(start -0.4318 0.3302)
							(mid -0.402042 0.402042)
							(end -0.3302 0.4318)
						)
						(arc
							(start 0.3302 0.4318)
							(mid 0.402042 0.402042)
							(end 0.4318 0.3302)
						)
						(arc
							(start 0.4318 -0.3302)
							(mid 0.402042 -0.402042)
							(end 0.3302 -0.4318)
						)
					)
					(width 0)
					(fill yes)
				)
			)
		)
		(pad "2" smd custom
			(at 0 0.762)
			(size 0.2159 0.2159)
			(layers "F.Cu" "F.Mask" "F.Paste")
			(net "DETECTOR_C")
			(options
				(clearance outline)
				(anchor circle)
			)
			(primitives
				(gr_poly
					(pts
						(arc
							(start -0.3302 -0.4318)
							(mid -0.402042 -0.402042)
							(end -0.4318 -0.3302)
						)
						(arc
							(start -0.4318 0.3302)
							(mid -0.402042 0.402042)
							(end -0.3302 0.4318)
						)
						(arc
							(start 0.3302 0.4318)
							(mid 0.402042 0.402042)
							(end 0.4318 0.3302)
						)
						(arc
							(start 0.4318 -0.3302)
							(mid 0.402042 -0.402042)
							(end 0.3302 -0.4318)
						)
					)
					(width 0)
					(fill yes)
				)
			)
		)
	)
	(footprint ""
		(layer "F.Cu")
		(at 107.061 -47.371 180)
		(property "Reference" "C364"
			(at 0 0 180)
			(layer "F.SilkS")
			(hide yes)
			(effects
				(font
					(size 1.27 1.27)
				)
			)
		)
		(property "Value" "SC47U16V0MX-GP"
			(at -0.00254 -4.78536 180)
			(unlocked yes)
			(layer "F.Fab")
			(hide yes)
			(effects
				(font
					(size 1.016 1.016)
					(thickness 0.1524)
				)
			)
		)
		(property "Device Type" "C1210H107"
			(at -0.00254 -6.38048 180)
			(unlocked yes)
			(layer "F.Fab")
			(hide yes)
			(effects
				(font
					(size 1.016 1.016)
					(thickness 0.1524)
				)
			)
		)
		(duplicate_pad_numbers_are_jumpers no)
		(fp_line
			(start 1.5748 2.3368)
			(end 1.5748 0.762)
			(stroke
				(width 0.1524)
				(type default)
			)
			(layer "F.SilkS")
		)
		(fp_line
			(start 1.5748 -0.762)
			(end 1.5748 -2.3368)
			(stroke
				(width 0.1524)
				(type default)
			)
			(layer "F.SilkS")
		)
		(fp_line
			(start 1.5748 -2.3368)
			(end -1.5748 -2.3368)
			(stroke
				(width 0.1524)
				(type default)
			)
			(layer "F.SilkS")
		)
		(fp_line
			(start -1.5748 2.3368)
			(end 1.5748 2.3368)
			(stroke
				(width 0.1524)
				(type default)
			)
			(layer "F.SilkS")
		)
		(fp_line
			(start -1.5748 0.762)
			(end -1.5748 2.3368)
			(stroke
				(width 0.1524)
				(type default)
			)
			(layer "F.SilkS")
		)
		(fp_line
			(start -1.5748 -2.3368)
			(end -1.5748 -0.762)
			(stroke
				(width 0.1524)
				(type default)
			)
			(layer "F.SilkS")
		)
		(fp_rect
			(start -1.651 2.413)
			(end 1.651 -2.413)
			(stroke
				(width 0)
				(type default)
			)
			(fill no)
			(layer "F.CrtYd")
		)
		(fp_poly
			(pts
				(xy 1.651 2.413) (xy 1.651 -2.413) (xy -1.651 -2.413) (xy -1.651 2.413)
			)
			(stroke
				(width 0)
				(type default)
			)
			(fill no)
			(layer "F.Fab")
		)
		(pad "1" smd rect
			(at 0 -1.4732 180)
			(size 2.794 1.397)
			(layers "F.Cu" "F.Mask" "F.Paste")
			(net "P12V")
		)
		(pad "2" smd rect
			(at 0 1.4732 180)
			(size 2.794 1.397)
			(layers "F.Cu" "F.Mask" "F.Paste")
			(net "GND")
		)
	)
	(footprint ""
		(layer "F.Cu")
		(at 11.634978 -99.280472 180)
		(property "Reference" "C344"
			(at 0 0 180)
			(layer "F.SilkS")
			(hide yes)
			(effects
				(font
					(size 1.27 1.27)
				)
			)
		)
		(property "Value" "SCD1U50V3KX-GP"
			(at 0 -2.8194 180)
			(unlocked yes)
			(layer "F.Fab")
			(hide yes)
			(effects
				(font
					(size 1.016 1.016)
					(thickness 0.1524)
				)
			)
		)
		(property "Device Type" "C603H36"
			(at 0 -4.3434 180)
			(unlocked yes)
			(layer "F.Fab")
			(hide yes)
			(effects
				(font
					(size 1.016 1.016)
					(thickness 0.1524)
				)
			)
		)
		(duplicate_pad_numbers_are_jumpers no)
		(fp_line
			(start 0.508 0)
			(end -0.508 0)
			(stroke
				(width 0.2032)
				(type default)
			)
			(layer "F.SilkS")
		)
		(fp_rect
			(start -0.5842 1.3335)
			(end 0.5842 -1.3335)
			(stroke
				(width 0)
				(type default)
			)
			(fill no)
			(layer "F.CrtYd")
		)
		(fp_rect
			(start -0.5842 1.3335)
			(end 0.5842 -1.3335)
			(stroke
				(width 0)
				(type default)
			)
			(fill no)
			(layer "F.Fab")
		)
		(pad "1" smd custom
			(at 0 -0.762 180)
			(size 0.2159 0.2159)
			(layers "F.Cu" "F.Mask" "F.Paste")
			(net "P3V3")
			(options
				(clearance outline)
				(anchor circle)
			)
			(primitives
				(gr_poly
					(pts
						(arc
							(start -0.3302 -0.4318)
							(mid -0.402042 -0.402042)
							(end -0.4318 -0.3302)
						)
						(arc
							(start -0.4318 0.3302)
							(mid -0.402042 0.402042)
							(end -0.3302 0.4318)
						)
						(arc
							(start 0.3302 0.4318)
							(mid 0.402042 0.402042)
							(end 0.4318 0.3302)
						)
						(arc
							(start 0.4318 -0.3302)
							(mid 0.402042 -0.402042)
							(end 0.3302 -0.4318)
						)
					)
					(width 0)
					(fill yes)
				)
			)
		)
		(pad "2" smd custom
			(at 0 0.762 180)
			(size 0.2159 0.2159)
			(layers "F.Cu" "F.Mask" "F.Paste")
			(net "GND")
			(options
				(clearance outline)
				(anchor circle)
			)
			(primitives
				(gr_poly
					(pts
						(arc
							(start -0.3302 -0.4318)
							(mid -0.402042 -0.402042)
							(end -0.4318 -0.3302)
						)
						(arc
							(start -0.4318 0.3302)
							(mid -0.402042 0.402042)
							(end -0.3302 0.4318)
						)
						(arc
							(start 0.3302 0.4318)
							(mid 0.402042 0.402042)
							(end 0.4318 0.3302)
						)
						(arc
							(start 0.4318 -0.3302)
							(mid 0.402042 -0.402042)
							(end 0.3302 -0.4318)
						)
					)
					(width 0)
					(fill yes)
				)
			)
		)
	)
)
